# BASEBOARD_FAB2 (Tioga Pass) — schematic netlist excerpt (pin names and nets, part order shuffled) for the footprints in the layout excerpt that follows; sources: Cadence DE-HDL packaged netlist, KiCad conversion of Wiwynn_Tioga_Pass_MB.brd

C1R22  CAP  10UF 6.3V 20% X6S  pkg 0603  page 139 : A = P3V3_STBY ; B = GND
R8E29  RES  0.0 5% EMPTY  pkg 0402  page 142 : A = FM_PE_BMC_WAKE_N ; B = FM_ALL_WAKE_N
R6P8  RES  42.2 1.0% EMPTY  pkg 0402  page 103 : A = CLK_100M_CPU1_BCLK1_DN ; B = GND

(kicad_pcb
	(version 20260206)
	(generator "pcbnew")
	(generator_version "10.0")
	(general
		(thickness 1.6)
		(legacy_teardrops no)
	)
	(paper "A4")
	(title_block
		(title "Wiwynn_Tioga_Pass_MB.brd")
		(comment 1 "Tioga Pass / footprints 3700-3702 of 4770")
	)
	(layers
		(0 "F.Cu" signal "TOP")
		(4 "In1.Cu" signal "L2GND")
		(6 "In2.Cu" signal "L3")
		(8 "In3.Cu" signal "L4GND")
		(10 "In4.Cu" signal "L5")
		(12 "In5.Cu" signal "L6GND")
		(14 "In6.Cu" signal "L7VCC")
		(16 "In7.Cu" signal "L8VCC")
		(18 "In8.Cu" signal "L9GND")
		(20 "In9.Cu" signal "L10")
		(22 "In10.Cu" signal "L11GND")
		(24 "In11.Cu" signal "L12")
		(26 "In12.Cu" signal "L13GND")
		(2 "B.Cu" signal "BOTTOM")
		(9 "F.Adhes" user "F.Adhesive")
		(11 "B.Adhes" user "B.Adhesive")
		(13 "F.Paste" user "Package Geometry/Pastemask Top")
		(15 "B.Paste" user "Package Geometry/Pastemask Bottom")
		(5 "F.SilkS" user "Ref Des/Silkscreen Top")
		(7 "B.SilkS" user "Ref Des/Silkscreen Bottom")
		(1 "F.Mask" user "Board Geometry/Soldermask Top")
		(3 "B.Mask" user "Board Geometry/Soldermask Bottom")
		(17 "Dwgs.User" user "User.Drawings")
		(19 "Cmts.User" user "User.Comments")
		(21 "Eco1.User" user "User.Eco1")
		(23 "Eco2.User" user "User.Eco2")
		(25 "Edge.Cuts" user "Board Geometry/Outline")
		(27 "Margin" user)
		(31 "F.CrtYd" user "Package Geometry/Place Bound Top")
		(29 "B.CrtYd" user "Package Geometry/Place Bound Bottom")
		(35 "F.Fab" user "Ref Des/Assembly Top")
		(33 "B.Fab" user "Ref Des/Assembly Bottom")
	)
	(footprint ""
		(layer "B.Cu")
		(at 479.923602 -58.772298 90)
		(property "Reference" "R8E29"
			(at 0 0 90)
			(layer "B.SilkS")
			(hide yes)
			(effects
				(font
					(size 1.27 1.27)
				)
				(justify mirror)
			)
		)
		(property "Value" ""
			(at 0 0 90)
			(layer "B.Fab")
			(effects
				(font
					(size 1.27 1.27)
				)
				(justify mirror)
			)
		)
		(duplicate_pad_numbers_are_jumpers no)
		(fp_poly
			(pts
				(xy 0.2794 -0.1016) (xy -0.2794 -0.1016) (xy -0.2794 0.9906) (xy 0.2794 0.9906)
			)
			(stroke
				(width 0)
				(type default)
			)
			(fill no)
			(layer "B.CrtYd")
		)
		(fp_line
			(start 0.2794 -0.1016)
			(end 0.2794 0.9906)
			(stroke
				(width 0.1)
				(type default)
			)
			(layer "B.Fab")
		)
		(fp_line
			(start -0.2794 -0.1016)
			(end 0.2794 -0.1016)
			(stroke
				(width 0.1)
				(type default)
			)
			(layer "B.Fab")
		)
		(fp_line
			(start 0.2794 0.9906)
			(end -0.2794 0.9906)
			(stroke
				(width 0.1)
				(type default)
			)
			(layer "B.Fab")
		)
		(fp_line
			(start -0.2794 0.9906)
			(end -0.2794 -0.1016)
			(stroke
				(width 0.1)
				(type default)
			)
			(layer "B.Fab")
		)
		(pad "1" smd rect
			(at 0 0 270)
			(size 0.508 0.508)
			(layers "B.Cu" "B.Mask" "B.Paste")
			(net "FM_PE_BMC_WAKE_N")
		)
		(pad "2" smd rect
			(at 0 0.889 270)
			(size 0.508 0.508)
			(layers "B.Cu" "B.Mask" "B.Paste")
			(net "FM_ALL_WAKE_N")
		)
		(zone
			(layer "B.Cu")
			(hatch none 0.5)
			(connect_pads
				(clearance 0)
			)
			(min_thickness 0.25)
			(keepout
				(tracks allowed)
				(vias not_allowed)
				(pads allowed)
				(copperpour not_allowed)
				(footprints allowed)
			)
			(placement
				(enabled no)
				(sheetname "")
			)
			(fill
				(thermal_gap 0.5)
				(thermal_bridge_width 0.5)
				(island_removal_mode 0)
			)
			(polygon
				(pts
					(xy 480.177602 -59.026298) (xy 480.177602 -58.518298) (xy 480.558602 -58.518298) (xy 480.558602 -59.026298)
				)
			)
		)
		(zone
			(layer "B.Cu")
			(hatch none 0.5)
			(connect_pads
				(clearance 0)
			)
			(min_thickness 0.25)
			(keepout
				(tracks not_allowed)
				(vias allowed)
				(pads allowed)
				(copperpour not_allowed)
				(footprints allowed)
			)
			(placement
				(enabled no)
				(sheetname "")
			)
			(fill
				(thermal_gap 0.5)
				(thermal_bridge_width 0.5)
				(island_removal_mode 0)
			)
			(polygon
				(pts
					(xy 480.558602 -59.026298) (xy 480.558602 -58.518298) (xy 480.177602 -58.518298) (xy 480.177602 -59.026298)
				)
			)
		)
	)
	(footprint ""
		(layer "B.Cu")
		(at 488.3404 -42.5196 -90)
		(property "Reference" "C1R22"
			(at 0 0 90)
			(layer "B.SilkS")
			(hide yes)
			(effects
				(font
					(size 1.27 1.27)
				)
				(justify mirror)
			)
		)
		(property "Value" ""
			(at 0 0 90)
			(layer "B.Fab")
			(effects
				(font
					(size 1.27 1.27)
				)
				(justify mirror)
			)
		)
		(duplicate_pad_numbers_are_jumpers no)
		(fp_poly
			(pts
				(xy 0.4953 -0.2032) (xy -0.4953 -0.2032) (xy -0.4953 1.6002) (xy 0.4953 1.6002)
			)
			(stroke
				(width 0)
				(type default)
			)
			(fill no)
			(layer "B.CrtYd")
		)
		(fp_line
			(start -0.4953 1.6002)
			(end 0.4953 1.6002)
			(stroke
				(width 0.1)
				(type default)
			)
			(layer "B.Fab")
		)
		(fp_line
			(start 0.4953 1.6002)
			(end 0.4953 -0.2032)
			(stroke
				(width 0.1)
				(type default)
			)
			(layer "B.Fab")
		)
		(fp_line
			(start -0.4953 -0.2032)
			(end -0.4953 1.6002)
			(stroke
				(width 0.1)
				(type default)
			)
			(layer "B.Fab")
		)
		(fp_line
			(start 0.4953 -0.2032)
			(end -0.4953 -0.2032)
			(stroke
				(width 0.1)
				(type default)
			)
			(layer "B.Fab")
		)
		(pad "1" smd rect
			(at 0 0 90)
			(size 0.762 0.889)
			(layers "B.Cu" "B.Mask" "B.Paste")
			(net "P3V3_STBY")
		)
		(pad "2" smd rect
			(at 0 1.397 90)
			(size 0.762 0.889)
			(layers "B.Cu" "B.Mask" "B.Paste")
			(net "GND")
		)
		(zone
			(layer "B.Cu")
			(hatch none 0.5)
			(connect_pads
				(clearance 0)
			)
			(min_thickness 0.25)
			(keepout
				(tracks not_allowed)
				(vias allowed)
				(pads allowed)
				(copperpour not_allowed)
				(footprints allowed)
			)
			(placement
				(enabled no)
				(sheetname "")
			)
			(fill
				(thermal_gap 0.5)
				(thermal_bridge_width 0.5)
				(island_removal_mode 0)
			)
			(polygon
				(pts
					(xy 487.8959 -42.1386) (xy 487.8959 -42.9006) (xy 487.3879 -42.9006) (xy 487.3879 -42.1386)
				)
			)
		)
	)
	(footprint ""
		(layer "B.Cu")
		(at 164.846 -87.757)
		(property "Reference" "R6P8"
			(at 0 0 0)
			(layer "B.SilkS")
			(hide yes)
			(effects
				(font
					(size 1.27 1.27)
				)
				(justify mirror)
			)
		)
		(property "Value" ""
			(at 0 0 0)
			(layer "B.Fab")
			(effects
				(font
					(size 1.27 1.27)
				)
				(justify mirror)
			)
		)
		(duplicate_pad_numbers_are_jumpers no)
		(fp_poly
			(pts
				(xy 0.2794 -0.1016) (xy -0.2794 -0.1016) (xy -0.2794 0.9906) (xy 0.2794 0.9906)
			)
			(stroke
				(width 0)
				(type default)
			)
			(fill no)
			(layer "B.CrtYd")
		)
		(fp_line
			(start -0.2794 -0.1016)
			(end 0.2794 -0.1016)
			(stroke
				(width 0.1)
				(type default)
			)
			(layer "B.Fab")
		)
		(fp_line
			(start -0.2794 0.9906)
			(end -0.2794 -0.1016)
			(stroke
				(width 0.1)
				(type default)
			)
			(layer "B.Fab")
		)
		(fp_line
			(start 0.2794 -0.1016)
			(end 0.2794 0.9906)
			(stroke
				(width 0.1)
				(type default)
			)
			(layer "B.Fab")
		)
		(fp_line
			(start 0.2794 0.9906)
			(end -0.2794 0.9906)
			(stroke
				(width 0.1)
				(type default)
			)
			(layer "B.Fab")
		)
		(pad "1" smd rect
			(at 0 0 180)
			(size 0.508 0.508)
			(layers "B.Cu" "B.Mask" "B.Paste")
			(net "CLK_100M_CPU1_BCLK1_DN")
		)
		(pad "2" smd rect
			(at 0 0.889 180)
			(size 0.508 0.508)
			(layers "B.Cu" "B.Mask" "B.Paste")
			(net "GND")
		)
		(zone
			(layer "B.Cu")
			(hatch none 0.5)
			(connect_pads
				(clearance 0)
			)
			(min_thickness 0.25)
			(keepout
				(tracks allowed)
				(vias not_allowed)
				(pads allowed)
				(copperpour not_allowed)
				(footprints allowed)
			)
			(placement
				(enabled no)
				(sheetname "")
			)
			(fill
				(thermal_gap 0.5)
				(thermal_bridge_width 0.5)
				(island_removal_mode 0)
			)
			(polygon
				(pts
					(xy 165.1 -87.503) (xy 164.592 -87.503) (xy 164.592 -87.122) (xy 165.1 -87.122)
				)
			)
		)
		(zone
			(layer "B.Cu")
			(hatch none 0.5)
			(connect_pads
				(clearance 0)
			)
			(min_thickness 0.25)
			(keepout
				(tracks not_allowed)
				(vias allowed)
				(pads allowed)
				(copperpour not_allowed)
				(footprints allowed)
			)
			(placement
				(enabled no)
				(sheetname "")
			)
			(fill
				(thermal_gap 0.5)
				(thermal_bridge_width 0.5)
				(island_removal_mode 0)
			)
			(polygon
				(pts
					(xy 165.1 -87.122) (xy 164.592 -87.122) (xy 164.592 -87.503) (xy 165.1 -87.503)
				)
			)
		)
	)
)
